(kicad_pcb
	(version 20260206)
	(generator "pcbnew")
	(generator_version "10.0")
	(general
		(thickness 1.6)
		(legacy_teardrops no)
	)
	(paper "A4")
	(title_block
		(title "Bryce Canyon_R.DPB_16317-1_OCP.brd")
		(comment 1 "Bryce Canyon / footprints 1534-1540 of 2099")
	)
	(layers
		(0 "F.Cu" signal "TOP")
		(4 "In1.Cu" signal "L2GND")
		(6 "In2.Cu" signal "L3")
		(8 "In3.Cu" signal "L4VCC")
		(10 "In4.Cu" signal "L5VCC")
		(12 "In5.Cu" signal "L6")
		(14 "In6.Cu" signal "L7GND")
		(2 "B.Cu" signal "BOTTOM")
		(9 "F.Adhes" user "F.Adhesive")
		(11 "B.Adhes" user "B.Adhesive")
		(13 "F.Paste" user "Package Geometry/Pastemask Top")
		(15 "B.Paste" user "Package Geometry/Pastemask Bottom")
		(5 "F.SilkS" user "Ref Des/Silkscreen Top")
		(7 "B.SilkS" user "Ref Des/Silkscreen Bottom")
		(1 "F.Mask" user "Board Geometry/Soldermask Top")
		(3 "B.Mask" user "Board Geometry/Soldermask Bottom")
		(17 "Dwgs.User" user "User.Drawings")
		(19 "Cmts.User" user "User.Comments")
		(21 "Eco1.User" user "User.Eco1")
		(23 "Eco2.User" user "User.Eco2")
		(25 "Edge.Cuts" user "Board Geometry/Outline")
		(27 "Margin" user)
		(31 "F.CrtYd" user "Package Geometry/Place Bound Top")
		(29 "B.CrtYd" user "Package Geometry/Place Bound Bottom")
		(35 "F.Fab" user "Ref Des/Assembly Top")
		(33 "B.Fab" user "Ref Des/Assembly Bottom")
	)
	(footprint ""
		(layer "F.Cu")
		(at 149.225 -248.4374 -90)
		(property "Reference" "R228"
			(at 0 0 270)
			(layer "F.SilkS")
			(hide yes)
			(effects
				(font
					(size 1.27 1.27)
				)
			)
		)
		(property "Value" "1KR2F-3-GP"
			(at 0.064008 -3.993896 270)
			(unlocked yes)
			(layer "F.Fab")
			(hide yes)
			(effects
				(font
					(size 1.016 1.016)
					(thickness 0.1524)
				)
			)
		)
		(property "Device Type" "R402H16"
			(at 0.064008 -5.517896 270)
			(unlocked yes)
			(layer "F.Fab")
			(hide yes)
			(effects
				(font
					(size 1.016 1.016)
					(thickness 0.1524)
				)
			)
		)
		(duplicate_pad_numbers_are_jumpers no)
		(fp_line
			(start -0.508 -0.9398)
			(end -0.508 0.9398)
			(stroke
				(width 0.1524)
				(type default)
			)
			(layer "F.SilkS")
		)
		(fp_line
			(start 0.508 -0.9398)
			(end -0.508 -0.9398)
			(stroke
				(width 0.1524)
				(type default)
			)
			(layer "F.SilkS")
		)
		(fp_rect
			(start -0.508 0.9398)
			(end 0.508 -0.9398)
			(stroke
				(width 0)
				(type default)
			)
			(fill no)
			(layer "F.CrtYd")
		)
		(fp_rect
			(start -0.508 0.9398)
			(end 0.508 -0.9398)
			(stroke
				(width 0)
				(type default)
			)
			(fill no)
			(layer "F.Fab")
		)
		(pad "1" smd custom
			(at 0 -0.4445 270)
			(size 0.1397 0.1397)
			(layers "F.Cu" "F.Mask" "F.Paste")
			(net "P3V3_STBY_B")
			(options
				(clearance outline)
				(anchor circle)
			)
			(primitives
				(gr_poly
					(pts
						(arc
							(start -0.1778 -0.2794)
							(mid -0.249642 -0.249642)
							(end -0.2794 -0.1778)
						)
						(arc
							(start -0.2794 0.1778)
							(mid -0.249642 0.249642)
							(end -0.1778 0.2794)
						)
						(arc
							(start 0.1778 0.2794)
							(mid 0.249642 0.249642)
							(end 0.2794 0.1778)
						)
						(arc
							(start 0.2794 -0.1778)
							(mid 0.249642 -0.249642)
							(end 0.1778 -0.2794)
						)
					)
					(width 0)
					(fill yes)
				)
			)
		)
		(pad "2" smd custom
			(at 0 0.4445 270)
			(size 0.1397 0.1397)
			(layers "F.Cu" "F.Mask" "F.Paste")
			(net "SW_PWR_R_HDD4")
			(options
				(clearance outline)
				(anchor circle)
			)
			(primitives
				(gr_poly
					(pts
						(arc
							(start -0.1778 -0.2794)
							(mid -0.249642 -0.249642)
							(end -0.2794 -0.1778)
						)
						(arc
							(start -0.2794 0.1778)
							(mid -0.249642 0.249642)
							(end -0.1778 0.2794)
						)
						(arc
							(start 0.1778 0.2794)
							(mid 0.249642 0.249642)
							(end 0.2794 0.1778)
						)
						(arc
							(start 0.2794 -0.1778)
							(mid 0.249642 -0.249642)
							(end 0.1778 -0.2794)
						)
					)
					(width 0)
					(fill yes)
				)
			)
		)
	)
	(footprint ""
		(layer "F.Cu")
		(at 424.434 -267.843 180)
		(property "Reference" "C147"
			(at 0 0 180)
			(layer "F.SilkS")
			(hide yes)
			(effects
				(font
					(size 1.27 1.27)
				)
			)
		)
		(property "Value" "SC1U16V3KX-5GP"
			(at 0 -2.8194 180)
			(unlocked yes)
			(layer "F.Fab")
			(hide yes)
			(effects
				(font
					(size 1.016 1.016)
					(thickness 0.1524)
				)
			)
		)
		(property "Device Type" "C603H36"
			(at 0 -4.3434 180)
			(unlocked yes)
			(layer "F.Fab")
			(hide yes)
			(effects
				(font
					(size 1.016 1.016)
					(thickness 0.1524)
				)
			)
		)
		(duplicate_pad_numbers_are_jumpers no)
		(fp_line
			(start 0.508 0)
			(end -0.508 0)
			(stroke
				(width 0.2032)
				(type default)
			)
			(layer "F.SilkS")
		)
		(fp_rect
			(start -0.5842 1.3335)
			(end 0.5842 -1.3335)
			(stroke
				(width 0)
				(type default)
			)
			(fill no)
			(layer "F.CrtYd")
		)
		(fp_rect
			(start -0.5842 1.3335)
			(end 0.5842 -1.3335)
			(stroke
				(width 0)
				(type default)
			)
			(fill no)
			(layer "F.Fab")
		)
		(pad "1" smd custom
			(at 0 -0.762 180)
			(size 0.2159 0.2159)
			(layers "F.Cu" "F.Mask" "F.Paste")
			(net "P5V_HDD9")
			(options
				(clearance outline)
				(anchor circle)
			)
			(primitives
				(gr_poly
					(pts
						(arc
							(start -0.3302 -0.4318)
							(mid -0.402042 -0.402042)
							(end -0.4318 -0.3302)
						)
						(arc
							(start -0.4318 0.3302)
							(mid -0.402042 0.402042)
							(end -0.3302 0.4318)
						)
						(arc
							(start 0.3302 0.4318)
							(mid 0.402042 0.402042)
							(end 0.4318 0.3302)
						)
						(arc
							(start 0.4318 -0.3302)
							(mid 0.402042 -0.402042)
							(end 0.3302 -0.4318)
						)
					)
					(width 0)
					(fill yes)
				)
			)
		)
		(pad "2" smd custom
			(at 0 0.762 180)
			(size 0.2159 0.2159)
			(layers "F.Cu" "F.Mask" "F.Paste")
			(net "GND")
			(options
				(clearance outline)
				(anchor circle)
			)
			(primitives
				(gr_poly
					(pts
						(arc
							(start -0.3302 -0.4318)
							(mid -0.402042 -0.402042)
							(end -0.4318 -0.3302)
						)
						(arc
							(start -0.4318 0.3302)
							(mid -0.402042 0.402042)
							(end -0.3302 0.4318)
						)
						(arc
							(start 0.3302 0.4318)
							(mid 0.402042 0.402042)
							(end 0.4318 0.3302)
						)
						(arc
							(start 0.4318 -0.3302)
							(mid 0.402042 -0.402042)
							(end 0.3302 -0.4318)
						)
					)
					(width 0)
					(fill yes)
				)
			)
		)
	)
	(footprint ""
		(layer "F.Cu")
		(at 338.074 -250.444 90)
		(property "Reference" "R266"
			(at 0 0 90)
			(layer "F.SilkS")
			(hide yes)
			(effects
				(font
					(size 1.27 1.27)
				)
			)
		)
		(property "Value" "200KR2F-L-GP"
			(at 0.064008 -3.993896 90)
			(unlocked yes)
			(layer "F.Fab")
			(hide yes)
			(effects
				(font
					(size 1.016 1.016)
					(thickness 0.1524)
				)
			)
		)
		(property "Device Type" "R402H16"
			(at 0.064008 -5.517896 90)
			(unlocked yes)
			(layer "F.Fab")
			(hide yes)
			(effects
				(font
					(size 1.016 1.016)
					(thickness 0.1524)
				)
			)
		)
		(duplicate_pad_numbers_are_jumpers no)
		(fp_line
			(start 0.508 -0.9398)
			(end -0.508 -0.9398)
			(stroke
				(width 0.1524)
				(type default)
			)
			(layer "F.SilkS")
		)
		(fp_line
			(start -0.508 -0.9398)
			(end -0.508 0.9398)
			(stroke
				(width 0.1524)
				(type default)
			)
			(layer "F.SilkS")
		)
		(fp_rect
			(start -0.508 0.9398)
			(end 0.508 -0.9398)
			(stroke
				(width 0)
				(type default)
			)
			(fill no)
			(layer "F.CrtYd")
		)
		(fp_rect
			(start -0.508 0.9398)
			(end 0.508 -0.9398)
			(stroke
				(width 0)
				(type default)
			)
			(fill no)
			(layer "F.Fab")
		)
		(pad "1" smd custom
			(at 0 -0.4445 90)
			(size 0.1397 0.1397)
			(layers "F.Cu" "F.Mask" "F.Paste")
			(net "SW_HDD_R6")
			(options
				(clearance outline)
				(anchor circle)
			)
			(primitives
				(gr_poly
					(pts
						(arc
							(start -0.1778 -0.2794)
							(mid -0.249642 -0.249642)
							(end -0.2794 -0.1778)
						)
						(arc
							(start -0.2794 0.1778)
							(mid -0.249642 0.249642)
							(end -0.1778 0.2794)
						)
						(arc
							(start 0.1778 0.2794)
							(mid 0.249642 0.249642)
							(end 0.2794 0.1778)
						)
						(arc
							(start 0.2794 -0.1778)
							(mid 0.249642 -0.249642)
							(end 0.1778 -0.2794)
						)
					)
					(width 0)
					(fill yes)
				)
			)
		)
		(pad "2" smd custom
			(at 0 0.4445 90)
			(size 0.1397 0.1397)
			(layers "F.Cu" "F.Mask" "F.Paste")
			(net "SW_HDD_N6")
			(options
				(clearance outline)
				(anchor circle)
			)
			(primitives
				(gr_poly
					(pts
						(arc
							(start -0.1778 -0.2794)
							(mid -0.249642 -0.249642)
							(end -0.2794 -0.1778)
						)
						(arc
							(start -0.2794 0.1778)
							(mid -0.249642 0.249642)
							(end -0.1778 0.2794)
						)
						(arc
							(start 0.1778 0.2794)
							(mid 0.249642 0.249642)
							(end 0.2794 0.1778)
						)
						(arc
							(start 0.2794 -0.1778)
							(mid 0.249642 -0.249642)
							(end 0.1778 -0.2794)
						)
					)
					(width 0)
					(fill yes)
				)
			)
		)
	)
	(footprint ""
		(layer "F.Cu")
		(at 311.6834 -340.812882)
		(property "Reference" "R160"
			(at 0 0 0)
			(layer "F.SilkS")
			(hide yes)
			(effects
				(font
					(size 1.27 1.27)
				)
			)
		)
		(property "Value" "4K7R2F-GP"
			(at 0.064008 -3.993896 0)
			(unlocked yes)
			(layer "F.Fab")
			(hide yes)
			(effects
				(font
					(size 1.016 1.016)
					(thickness 0.1524)
				)
			)
		)
		(property "Device Type" "R402H16"
			(at 0.064008 -5.517896 0)
			(unlocked yes)
			(layer "F.Fab")
			(hide yes)
			(effects
				(font
					(size 1.016 1.016)
					(thickness 0.1524)
				)
			)
		)
		(duplicate_pad_numbers_are_jumpers no)
		(fp_line
			(start -0.508 -0.9398)
			(end -0.508 0.9398)
			(stroke
				(width 0.1524)
				(type default)
			)
			(layer "F.SilkS")
		)
		(fp_line
			(start 0.508 -0.9398)
			(end -0.508 -0.9398)
			(stroke
				(width 0.1524)
				(type default)
			)
			(layer "F.SilkS")
		)
		(fp_rect
			(start -0.508 0.9398)
			(end 0.508 -0.9398)
			(stroke
				(width 0)
				(type default)
			)
			(fill no)
			(layer "F.CrtYd")
		)
		(fp_rect
			(start -0.508 0.9398)
			(end 0.508 -0.9398)
			(stroke
				(width 0)
				(type default)
			)
			(fill no)
			(layer "F.Fab")
		)
		(pad "1" smd custom
			(at 0 -0.4445)
			(size 0.1397 0.1397)
			(layers "F.Cu" "F.Mask" "F.Paste")
			(net "P3V3_IN")
			(options
				(clearance outline)
				(anchor circle)
			)
			(primitives
				(gr_poly
					(pts
						(arc
							(start -0.1778 -0.2794)
							(mid -0.249642 -0.249642)
							(end -0.2794 -0.1778)
						)
						(arc
							(start -0.2794 0.1778)
							(mid -0.249642 0.249642)
							(end -0.1778 0.2794)
						)
						(arc
							(start 0.1778 0.2794)
							(mid 0.249642 0.249642)
							(end 0.2794 0.1778)
						)
						(arc
							(start 0.2794 -0.1778)
							(mid 0.249642 -0.249642)
							(end 0.1778 -0.2794)
						)
					)
					(width 0)
					(fill yes)
				)
			)
		)
		(pad "2" smd custom
			(at 0 0.4445)
			(size 0.1397 0.1397)
			(layers "F.Cu" "F.Mask" "F.Paste")
			(net "THERMHOT#_D")
			(options
				(clearance outline)
				(anchor circle)
			)
			(primitives
				(gr_poly
					(pts
						(arc
							(start -0.1778 -0.2794)
							(mid -0.249642 -0.249642)
							(end -0.2794 -0.1778)
						)
						(arc
							(start -0.2794 0.1778)
							(mid -0.249642 0.249642)
							(end -0.1778 0.2794)
						)
						(arc
							(start 0.1778 0.2794)
							(mid 0.249642 0.249642)
							(end 0.2794 0.1778)
						)
						(arc
							(start 0.2794 -0.1778)
							(mid 0.249642 -0.249642)
							(end 0.1778 -0.2794)
						)
					)
					(width 0)
					(fill yes)
				)
			)
		)
	)
	(footprint ""
		(layer "F.Cu")
		(at 181.991 -45.466 180)
		(property "Reference" "C413"
			(at 0 0 180)
			(layer "F.SilkS")
			(hide yes)
			(effects
				(font
					(size 1.27 1.27)
				)
			)
		)
		(property "Value" "SC1U25V3KX-GP"
			(at 0 -2.8194 180)
			(unlocked yes)
			(layer "F.Fab")
			(hide yes)
			(effects
				(font
					(size 1.016 1.016)
					(thickness 0.1524)
				)
			)
		)
		(property "Device Type" "C603H36"
			(at 0 -4.3434 180)
			(unlocked yes)
			(layer "F.Fab")
			(hide yes)
			(effects
				(font
					(size 1.016 1.016)
					(thickness 0.1524)
				)
			)
		)
		(duplicate_pad_numbers_are_jumpers no)
		(fp_line
			(start 0.508 0)
			(end -0.508 0)
			(stroke
				(width 0.2032)
				(type default)
			)
			(layer "F.SilkS")
		)
		(fp_rect
			(start -0.5842 1.3335)
			(end 0.5842 -1.3335)
			(stroke
				(width 0)
				(type default)
			)
			(fill no)
			(layer "F.CrtYd")
		)
		(fp_rect
			(start -0.5842 1.3335)
			(end 0.5842 -1.3335)
			(stroke
				(width 0)
				(type default)
			)
			(fill no)
			(layer "F.Fab")
		)
		(pad "1" smd custom
			(at 0 -0.762 180)
			(size 0.2159 0.2159)
			(layers "F.Cu" "F.Mask" "F.Paste")
			(net "P12V_HDD29")
			(options
				(clearance outline)
				(anchor circle)
			)
			(primitives
				(gr_poly
					(pts
						(arc
							(start -0.3302 -0.4318)
							(mid -0.402042 -0.402042)
							(end -0.4318 -0.3302)
						)
						(arc
							(start -0.4318 0.3302)
							(mid -0.402042 0.402042)
							(end -0.3302 0.4318)
						)
						(arc
							(start 0.3302 0.4318)
							(mid 0.402042 0.402042)
							(end 0.4318 0.3302)
						)
						(arc
							(start 0.4318 -0.3302)
							(mid 0.402042 -0.402042)
							(end 0.3302 -0.4318)
						)
					)
					(width 0)
					(fill yes)
				)
			)
		)
		(pad "2" smd custom
			(at 0 0.762 180)
			(size 0.2159 0.2159)
			(layers "F.Cu" "F.Mask" "F.Paste")
			(net "GND")
			(options
				(clearance outline)
				(anchor circle)
			)
			(primitives
				(gr_poly
					(pts
						(arc
							(start -0.3302 -0.4318)
							(mid -0.402042 -0.402042)
							(end -0.4318 -0.3302)
						)
						(arc
							(start -0.4318 0.3302)
							(mid -0.402042 0.402042)
							(end -0.3302 0.4318)
						)
						(arc
							(start 0.3302 0.4318)
							(mid 0.402042 0.402042)
							(end 0.4318 0.3302)
						)
						(arc
							(start 0.4318 -0.3302)
							(mid 0.402042 -0.402042)
							(end 0.3302 -0.4318)
						)
					)
					(width 0)
					(fill yes)
				)
			)
		)
	)
	(footprint ""
		(layer "F.Cu")
		(at 402.843746 -214.860378 90)
		(property "Reference" "Q252"
			(at 0 0 90)
			(layer "F.SilkS")
			(hide yes)
			(effects
				(font
					(size 1.27 1.27)
				)
			)
		)
		(property "Value" "SSM3K324R-GP"
			(at 0.127 -8.9662 90)
			(unlocked yes)
			(layer "F.Fab")
			(hide yes)
			(effects
				(font
					(size 1.016 1.016)
					(thickness 0.1524)
				)
			)
		)
		(property "Device Type" "SOT23DGS2D4H35"
			(at 0.127 -10.4902 90)
			(unlocked yes)
			(layer "F.Fab")
			(hide yes)
			(effects
				(font
					(size 1.016 1.016)
					(thickness 0.1524)
				)
			)
		)
		(duplicate_pad_numbers_are_jumpers no)
		(fp_line
			(start 1.651 -1.778)
			(end -1.651 -1.778)
			(stroke
				(width 0.1524)
				(type default)
			)
			(layer "F.SilkS")
		)
		(fp_line
			(start -1.651 -1.778)
			(end -1.651 1.778)
			(stroke
				(width 0.1524)
				(type default)
			)
			(layer "F.SilkS")
		)
		(fp_line
			(start 1.651 1.778)
			(end 1.651 -1.778)
			(stroke
				(width 0.1524)
				(type default)
			)
			(layer "F.SilkS")
		)
		(fp_line
			(start -1.651 1.778)
			(end 1.651 1.778)
			(stroke
				(width 0.1524)
				(type default)
			)
			(layer "F.SilkS")
		)
		(fp_poly
			(pts
				(xy -1.778 1.8796) (xy -1.778 -1.8796) (xy 1.778 -1.8796) (xy 1.778 1.8796)
			)
			(stroke
				(width 0)
				(type default)
			)
			(fill no)
			(layer "F.CrtYd")
		)
		(fp_poly
			(pts
				(xy -1.778 1.8796) (xy -1.778 -1.8796) (xy 1.778 -1.8796) (xy 1.778 1.8796)
			)
			(stroke
				(width 0)
				(type default)
			)
			(fill no)
			(layer "F.Fab")
		)
		(pad "D" smd custom
			(at 0 -0.9525 90)
			(size 0.1905 0.1905)
			(layers "F.Cu" "F.Mask" "F.Paste")
			(net "DRV_ACT_9_N")
			(options
				(clearance outline)
				(anchor circle)
			)
			(primitives
				(gr_poly
					(pts
						(arc
							(start -0.1778 0.5715)
							(mid -0.321484 0.511984)
							(end -0.381 0.3683)
						)
						(arc
							(start -0.381 -0.3683)
							(mid -0.321484 -0.511984)
							(end -0.1778 -0.5715)
						)
						(arc
							(start 0.1778 -0.5715)
							(mid 0.321484 -0.511984)
							(end 0.381 -0.3683)
						)
						(arc
							(start 0.381 0.3683)
							(mid 0.321484 0.511984)
							(end 0.1778 0.5715)
						)
					)
					(width 0)
					(fill yes)
				)
			)
		)
		(pad "G" smd custom
			(at -0.98425 0.9525 90)
			(size 0.1905 0.1905)
			(layers "F.Cu" "F.Mask" "F.Paste")
			(net "DRIVE_B_9_ACT")
			(options
				(clearance outline)
				(anchor circle)
			)
			(primitives
				(gr_poly
					(pts
						(arc
							(start -0.1778 0.5715)
							(mid -0.321484 0.511984)
							(end -0.381 0.3683)
						)
						(arc
							(start -0.381 -0.3683)
							(mid -0.321484 -0.511984)
							(end -0.1778 -0.5715)
						)
						(arc
							(start 0.1778 -0.5715)
							(mid 0.321484 -0.511984)
							(end 0.381 -0.3683)
						)
						(arc
							(start 0.381 0.3683)
							(mid 0.321484 0.511984)
							(end 0.1778 0.5715)
						)
					)
					(width 0)
					(fill yes)
				)
			)
		)
		(pad "S" smd custom
			(at 0.98425 0.9525 90)
			(size 0.1905 0.1905)
			(layers "F.Cu" "F.Mask" "F.Paste")
			(net "GND")
			(options
				(clearance outline)
				(anchor circle)
			)
			(primitives
				(gr_poly
					(pts
						(arc
							(start -0.1778 0.5715)
							(mid -0.321484 0.511984)
							(end -0.381 0.3683)
						)
						(arc
							(start -0.381 -0.3683)
							(mid -0.321484 -0.511984)
							(end -0.1778 -0.5715)
						)
						(arc
							(start 0.1778 -0.5715)
							(mid 0.321484 -0.511984)
							(end 0.381 -0.3683)
						)
						(arc
							(start 0.381 0.3683)
							(mid 0.321484 0.511984)
							(end 0.1778 0.5715)
						)
					)
					(width 0)
					(fill yes)
				)
			)
		)
	)
	(footprint ""
		(layer "F.Cu")
		(at 32.4104 -31.5976)
		(property "Reference" "C349"
			(at 0 0 0)
			(layer "F.SilkS")
			(hide yes)
			(effects
				(font
					(size 1.27 1.27)
				)
			)
		)
		(property "Value" "SCD01U50V2KX-1GP"
			(at 1.1811 -2.7051 0)
			(unlocked yes)
			(layer "F.Fab")
			(hide yes)
			(effects
				(font
					(size 1.016 1.016)
					(thickness 0.1524)
				)
			)
		)
		(property "Device Type" "C402H22"
			(at 1.1811 -4.2291 0)
			(unlocked yes)
			(layer "F.Fab")
			(hide yes)
			(effects
				(font
					(size 1.016 1.016)
					(thickness 0.1524)
				)
			)
		)
		(duplicate_pad_numbers_are_jumpers no)
		(fp_rect
			(start -0.4318 0.9525)
			(end 0.4318 -0.9525)
			(stroke
				(width 0)
				(type default)
			)
			(fill no)
			(layer "F.CrtYd")
		)
		(fp_rect
			(start -0.4318 0.9525)
			(end 0.4318 -0.9525)
			(stroke
				(width 0)
				(type default)
			)
			(fill no)
			(layer "F.Fab")
		)
		(pad "1" smd custom
			(at 0 -0.4445)
			(size 0.1524 0.1524)
			(layers "F.Cu" "F.Mask" "F.Paste")
			(net "HDD_PRSNT_24")
			(options
				(clearance outline)
				(anchor circle)
			)
			(primitives
				(gr_poly
					(pts
						(arc
							(start 0.3048 -0.2032)
							(mid 0.275042 -0.275042)
							(end 0.2032 -0.3048)
						)
						(arc
							(start -0.2032 -0.3048)
							(mid -0.275042 -0.275042)
							(end -0.3048 -0.2032)
						)
						(arc
							(start -0.3048 0.2032)
							(mid -0.275042 0.275042)
							(end -0.2032 0.3048)
						)
						(arc
							(start 0.2032 0.3048)
							(mid 0.275042 0.275042)
							(end 0.3048 0.2032)
						)
					)
					(width 0)
					(fill yes)
				)
			)
		)
		(pad "2" smd custom
			(at 0 0.4445)
			(size 0.1524 0.1524)
			(layers "F.Cu" "F.Mask" "F.Paste")
			(net "GND")
			(options
				(clearance outline)
				(anchor circle)
			)
			(primitives
				(gr_poly
					(pts
						(arc
							(start 0.3048 -0.2032)
							(mid 0.275042 -0.275042)
							(end 0.2032 -0.3048)
						)
						(arc
							(start -0.2032 -0.3048)
							(mid -0.275042 -0.275042)
							(end -0.3048 -0.2032)
						)
						(arc
							(start -0.3048 0.2032)
							(mid -0.275042 0.275042)
							(end -0.2032 0.3048)
						)
						(arc
							(start 0.2032 0.3048)
							(mid 0.275042 0.275042)
							(end 0.3048 0.2032)
						)
					)
					(width 0)
					(fill yes)
				)
			)
		)
	)
)
